Altium Designer Pick and Place Locations
C:\Users\<user>\Desktop\WorkNotes\Projects\PTP\TimeCardNPI\HackDesign\WIP\ECAD\Project Outputs for Timingcard_PROJECT\Pick Place for TimeCard-DC-V8_EXP.txt

========================================================================================================================
File Design Information:

Date:       27/01/23
Time:       09:13
Revision:   Not in VersionControl
Variant:    No variations
Units used: mil

Designator Comment                 Layer       Footprint                       Center-X(mil) Center-Y(mil) Rotation Description                                                                                                                    
R110       DNI_4.7K_0402           TopLayer    RESC1005X40X25LL05T05           677.165       -1177.165     180      "Chip Resistor, 4.7 KOhm, +/- 1%, 0.1 W, -55 to 155 degC, 0402 (1005 Metric), RoHS, Tape and Reel"                             
R109       4.7K_0402               TopLayer    RESC1005X40X25LL05T05           677.165       -1102.362     0        "Chip Resistor, 4.7 KOhm, +/- 1%, 0.1 W, -55 to 155 degC, 0402 (1005 Metric), RoHS, Tape and Reel"                             
R108       4.7K_0402               TopLayer    RESC1005X40X25LL05T05           677.165       -1137.795     0        "Chip Resistor, 4.7 KOhm, +/- 1%, 0.1 W, -55 to 155 degC, 0402 (1005 Metric), RoHS, Tape and Reel"                             
R107       DNI_49.9_1%_0402        TopLayer    RESC1005X40X25LL05T10           2598.425      -1204.724     270      ""                                                                                                                             
R106       DNI_49.9_1%_0402        TopLayer    RESC1005X40X25LL05T10           2578.740      -1047.244     180      ""                                                                                                                             
R105       DNI_49.9_1%_0402        TopLayer    RESC1005X40X25LL05T10           2389.764      -1224.409     180      ""                                                                                                                             
R104       DNI_49.9_1%_0402        TopLayer    RESC1005X40X25LL05T10           2350.394      -1153.543     90       ""                                                                                                                             
R103       DNI_27_1%_0402          TopLayer    RESC1005X40X25NL05T05           5757.874      -1062.992     0        ""                                                                                                                             
R102       DNI_27_1%_0402          TopLayer    RESC1005X40X25NL05T05           5834.646      -807.087      0        ""                                                                                                                             
R101       DNI_27_1%_0402          TopLayer    RESC1005X40X25NL05T05           6062.992      -1011.811     0        ""                                                                                                                             
R100       DNI_27_1%_0402          TopLayer    RESC1005X40X25NL05T05           6100.394      -818.898      0        ""                                                                                                                             
U23        TMUX1072RUTR            TopLayer    FP-RUT0012A-MFG                 2484.252      -1212.598     90       "IC SWITCH SPDT DUAL 12UQFN"                                                                                                   
U22        TMUX1072RUTR            TopLayer    FP-RUT0012A-MFG                 5842.520      -933.071      0        "IC SWITCH SPDT DUAL 12UQFN"                                                                                                   
U21        TMUX1072RUTR            TopLayer    FP-RUT0012A-MFG                 6171.260      -933.071      0        "IC SWITCH SPDT DUAL 12UQFN"                                                                                                   
U20        FT234XD-R               TopLayer    FP-DFN-12-IPC_B                 6854.331      -531.496      90       "IC USB SERIAL BASIC UART 12DFN"                                                                                               
SW1        A6H-2102                TopLayer    FP-A6H-2102-MFG                 4236.221      -1248.032     0        "SWITCH SLIDE DIP SPST 25MA 24V"                                                                                               
R99        49.9_1%_0402            TopLayer    RESC1005X40X25LL05T10           2539.370      -1307.087     180      ""                                                                                                                             
R98        49.9_1%_0402            TopLayer    RESC1005X40X25LL05T10           2555.118      -1153.543     180      ""                                                                                                                             
R97        49.9_1%_0402            TopLayer    RESC1005X40X25LL05T10           2440.945      -1307.087     0        ""                                                                                                                             
R96        49.9_1%_0402            TopLayer    RESC1005X40X25LL05T10           2440.945      -1141.732     0        ""                                                                                                                             
R95        200_1%_0402             TopLayer    FP-ERJ2RK-IPC_A                 4097.301      -1177.867     270      "RES SMD 200 OHM 1% 1/10W 0402"                                                                                                
R94        200_1%_0402             TopLayer    FP-ERJ2RK-IPC_A                 4366.142      -1188.892     270      "RES SMD 200 OHM 1% 1/10W 0402"                                                                                                
R93        27_1%_0402              TopLayer    RESC1005X40X25NL05T05           5736.221      -1003.937     0        ""                                                                                                                             
R92        27_1%_0402              TopLayer    RESC1005X40X25NL05T05           5944.882      -980.315      180      ""                                                                                                                             
R91        27_1%_0402              TopLayer    RESC1005X40X25NL05T05           5740.158      -881.890      0        ""                                                                                                                             
R90        27_1%_0402              TopLayer    RESC1005X40X25NL05T05           5940.945      -850.394      270      ""                                                                                                                             
R89        10K_1%_0402             TopLayer    RESC1005X40X25LL05T10           4381.890      -1110.236     180      ""                                                                                                                             
R88        10K_1%_0402             TopLayer    RESC1005X40X25LL05T10           4081.693      -1106.299     0        ""                                                                                                                             
R87        27_1%_0402              TopLayer    RESC1005X40X25NL05T05           6066.929      -952.756      0        ""                                                                                                                             
R86        27_1%_0402              TopLayer    RESC1005X40X25NL05T05           6279.528      -996.063      180      ""                                                                                                                             
R85        27_1%_0402              TopLayer    RESC1005X40X25NL05T05           6066.929      -897.638      0        ""                                                                                                                             
R84        27_1%_0402              TopLayer    RESC1005X40X25NL05T05           6275.591      -866.142      180      ""                                                                                                                             
R83        15K_1%_0402             TopLayer    FP-ERJ2R-MFG                    6858.268      -275.591      270      "RES SMD 15K OHM 1% 1/10W 0402"                                                                                                
R82        10K_1%_0402             TopLayer    RESC1005X40X25LL05T10           6791.339      -688.976      0        ""                                                                                                                             
R81        27_1%_0402              TopLayer    RESC1005X40X25NL05T05           6712.598      -811.024      90       ""                                                                                                                             
J43        2049261103              TopLayer    FP-2049261103-MFG               6884.842      -889.764      90       "CONN RCPT USB2.0 MICRO B SMD R/A"                                                                                             
FB1        600ohm_1.3A_0603        TopLayer    FP-BLM18-0_15-t0_8-IPC_A        6724.409      -1039.370     270      "Chip Ferrite Bead, 0603, 600O @ 100MHz, 0.15O, 25%, 1.3A"                                                                     
D25        SML-LX0603IW-TR         TopLayer    FP-SML-LX0603IW-TR-MFG          4098.425      -1299.213     270      "LED RED DIFFUSED SMD"                                                                                                         
D24        SML-LX0603IW-TR         TopLayer    FP-SML-LX0603IW-TR-MFG          4366.142      -1295.276     270      "LED RED DIFFUSED SMD"                                                                                                         
C96        0.1uF_25V_0402          TopLayer    FP-0402-L_1_0_1-W_0_5_0_1-IPC_C 2503.937      -1106.299     90       "General Purpose Ceramic Capacitor, 0402, 100nF, 10%, X7R, 15%, 25V"                                                           
C95        0.1uF_25V_0402          TopLayer    FP-0402-L_1_0_1-W_0_5_0_1-IPC_C 5972.441      -921.260      90       "General Purpose Ceramic Capacitor, 0402, 100nF, 10%, X7R, 15%, 25V"                                                           
C94        0.1uF_25V_0402          TopLayer    FP-0402-L_1_0_1-W_0_5_0_1-IPC_C 6275.591      -933.071      0        "General Purpose Ceramic Capacitor, 0402, 100nF, 10%, X7R, 15%, 25V"                                                           
C93        0.1uF_25V_0402          TopLayer    FP-0402-L_1_0_1-W_0_5_0_1-IPC_C 6866.142      -377.953      90       "General Purpose Ceramic Capacitor, 0402, 100nF, 10%, X7R, 15%, 25V"                                                           
C92        0.1uF_25V_0402          TopLayer    FP-0402-L_1_0_1-W_0_5_0_1-IPC_C 6940.945      -379.310      90       "General Purpose Ceramic Capacitor, 0402, 100nF, 10%, X7R, 15%, 25V"                                                           
C91        10nF_50V_0402           TopLayer    FP-CC0402-MFG                   6795.276      -318.898      90       "CAP CER 10000PF 50V X7R 0402"                                                                                                 
C90        4.7uF_16V_0402          TopLayer    FP-CL829-IPC_C                  6641.732      -1106.299     180      "Cap Ceramic 4.7uF 16V X5R ±20% SMD 0402 +85°C Paper T/R"                                                                      
C89        0.1uF_25V_0402          TopLayer    FP-0402-L_1_0_1-W_0_5_0_1-IPC_C 6937.008      -661.417      0        "General Purpose Ceramic Capacitor, 0402, 100nF, 10%, X7R, 15%, 25V"                                                           
C88        47pF_50V_0402           TopLayer    CAPC1005X55X25LL05T10           6625.984      -811.024      270      ""                                                                                                                             
C87        47pF_50V_0402           TopLayer    CAPC1005X55X25LL05T10           6755.905      -783.465      270      ""                                                                                                                             
C86        10nF_50V_0402           TopLayer    FP-CC0402-MFG                   6696.850      -944.882      180      "CAP CER 10000PF 50V X7R 0402"                                                                                                 
D23        SMDJ12A                 TopLayer    FP-DO-214AB_SMC_J-Bend-MFG      5649.606      -1692.913     180      "TVS DIODE 12V 19.9V DO214AB"                                                                                                  
R77        200_1%_0402             TopLayer    FP-ERJ2RK-IPC_A                 6862.205      -3157.480     180      "RES SMD 200 OHM 1% 1/10W 0402"                                                                                                
D20        SML-LX0603IW-TR         TopLayer    FP-SML-LX0603IW-TR-MFG          6728.346      -3157.480     180      "LED RED DIFFUSED SMD"                                                                                                         
D22        SD103AWS-7-F            TopLayer    FP-SOD323-MFG                   6196.850      -2960.630     0        "DIODE SCHOTTKY 40V 350MA SOD323"                                                                                              
D21        SD103AWS-7-F            TopLayer    FP-SOD323-MFG                   6307.087      -2338.583     0        "DIODE SCHOTTKY 40V 350MA SOD323"                                                                                              
U19        INA219BIDR              TopLayer    FP-D0008A-MFG                   6614.173      -3000.000     180      "IC MONITOR PWR/CURR BIDIR 8-SOIC"                                                                                             
U18        MIC24052YJL-TR          TopLayer    QFN28_5X6_MCH                   5736.221      -2720.472     90       "No Description Available"                                                                                                     
U17        INA219BIDR              TopLayer    FP-D0008A-MFG                   6692.913      -2283.465     180      "IC MONITOR PWR/CURR BIDIR 8-SOIC"                                                                                             
R80        0_1%_0402               TopLayer    RESC1005X40X25LL05T05           6822.834      -3062.992     0        "Chip Resistor, 0 Ohm, 0.1 W, -55 to 155 degC, 0402 (1005 Metric), RoHS, Tape and Reel"                                        
R79        0_1%_0402               TopLayer    RESC1005X40X25LL05T05           6822.834      -3019.685     0        "Chip Resistor, 0 Ohm, 0.1 W, -55 to 155 degC, 0402 (1005 Metric), RoHS, Tape and Reel"                                        
R78        787_1%_0402             TopLayer    RESC1005X40X25NL10T10           5501.969      -2659.449     0        ""                                                                                                                             
R76        2.49K_1%_0402           TopLayer    RESC1005X40X25NL05T10           5529.528      -2596.457     90       ""                                                                                                                             
R75        19.6K_1%_0402           TopLayer    RESC1005X40X25NL05T10           5834.646      -2854.331     0        ""                                                                                                                             
R74        2.21_1%_0402            TopLayer    RESC1005X40X25ML05T10           5500.984      -2850.394     0        ""                                                                                                                             
R73        1.21_1%_0402            TopLayer    RESC1005X40X25LL10T10           5940.945      -2838.583     90       ""                                                                                                                             
R72        2mOhm_1%_1206           TopLayer    RESC3216X89X64NL25T25           6393.701      -2692.913     0        ""                                                                                                                             
R71        2.21_1%_0402            TopLayer    RESC1005X40X25ML05T10           5834.646      -2897.638     0        ""                                                                                                                             
R70        1.21_1%_0402            TopLayer    RESC0402(1005)_N                5606.299      -2866.142     0        "1R21 0.063W 1% 0402 (1005 Metric)  SMD"                                                                                       
R69        1.21_1%_0402            TopLayer    RESC0402(1005)_N                6078.740      -2952.756     270      "1R21 0.063W 1% 0402 (1005 Metric)  SMD"                                                                                       
R68        4.7K_0402               TopLayer    RESC1005X40X25LL05T05           5503.937      -2708.661     0        "Chip Resistor, 4.7 KOhm, +/- 1%, 0.1 W, -55 to 155 degC, 0402 (1005 Metric), RoHS, Tape and Reel"                             
R67        4.7K_0402               TopLayer    RESC1005X40X25LL05T05           5503.937      -2748.032     0        "Chip Resistor, 4.7 KOhm, +/- 1%, 0.1 W, -55 to 155 degC, 0402 (1005 Metric), RoHS, Tape and Reel"                             
R66        0_1%_0402               TopLayer    RESC1005X40X25LL05T05           6736.220      -2421.260     180      "Chip Resistor, 0 Ohm, 0.1 W, -55 to 155 degC, 0402 (1005 Metric), RoHS, Tape and Reel"                                        
R65        0_1%_0402               TopLayer    RESC1005X40X25LL05T05           6677.165      -2437.008     270      "Chip Resistor, 0 Ohm, 0.1 W, -55 to 155 degC, 0402 (1005 Metric), RoHS, Tape and Reel"                                        
R64        0_1%_0402               TopLayer    RESC1005X40X25LL05T05           5641.732      -1094.488     0        "Chip Resistor, 0 Ohm, 0.1 W, -55 to 155 degC, 0402 (1005 Metric), RoHS, Tape and Reel"                                        
R63        470_1%_0402             TopLayer    RESC1005X40X25ML05T10           5519.685      -2003.937     0        ""                                                                                                                             
R62        0_1%_0402               TopLayer    RESC1005X40X25LL05T05           5519.685      -1090.551     180      "Chip Resistor, 0 Ohm, 0.1 W, -55 to 155 degC, 0402 (1005 Metric), RoHS, Tape and Reel"                                        
R61        2.49K_1%_0402           TopLayer    RESC1005X40X25NL05T10           5661.417      -1996.063     90       ""                                                                                                                             
R60        19.6K_1%_0402           TopLayer    RESC1005X40X25NL05T10           5992.126      -2299.213     90       ""                                                                                                                             
R59        2.21_1%_0402            TopLayer    RESC1005X40X25ML05T10           5547.244      -2133.858     270      ""                                                                                                                             
C85        10uF_16V_0603           TopLayer    FP-0603-L_1_6_0_2-W_0_8_0-MFG   6433.071      -2948.819     270      "Multilayer Ceramic Capacitor 10uF 16V X5R 20% SMD 0603 T/R"                                                                   
C84        0.1uF_0402              TopLayer    CAPC1005X56X25NL10T15           6645.669      -2830.709     180      ""                                                                                                                             
C83        0.1uF_25V_0402          TopLayer    FP-0402-L_1_0_1-W_0_5_0_1-IPC_C 6417.323      -2779.528     180      "General Purpose Ceramic Capacitor, 0402, 100nF, 10%, X7R, 15%, 25V"                                                           
C82        1uF_16V_0402            TopLayer    FP-0402-L_1_0_0_05-W_0_5-IPC_A  6645.669      -2763.780     0        None                                                                                                                           
C81        2.2uF_16V_0402          TopLayer    FP-C1005-050-0_05-IPC_A         6653.800      -2523.028     0        "Multilayer Ceramic Capacitors 2.2µF ±10% 16V X5R SMD 0402"                                                                    
C80        10uF_16V_0603           TopLayer    FP-0603-L_1_6_0_2-W_0_8_0-MFG   6653.543      -2602.362     0        "Multilayer Ceramic Capacitor 10uF 16V X5R 20% SMD 0603 T/R"                                                                   
C79        100uF_16V_2917          TopLayer    FP-T495D107K016ATE125-MFG       6433.071      -2543.307     0        "CAP TANT 100UF 10% 16V 2917"                                                                                                  
C78        47uF_16V_1206           TopLayer    FP-C3216-160-0_2-MFG            6641.732      -2685.039     0        "Multilayer Ceramic Capacitors 47uF ±20% 16V X5R SMD 1206"                                                                     
C77        4.7uF_50V_1206          TopLayer    FP-GRM31C-0_2-e0_3_0_8-IPC_C    5944.882      -2535.433     90       "Chip Multilayer Ceramic Capacitors for General Purpose, 1206, 4.7uF, X7R, 15%, 10%, 50V"                                      
C76        4.7uF_50V_1206          TopLayer    FP-GRM31C-0_2-e0_3_0_8-IPC_C    6055.118      -2539.370     90       "Chip Multilayer Ceramic Capacitors for General Purpose, 1206, 4.7uF, X7R, 15%, 10%, 50V"                                      
C75        100uF_16V_2917          TopLayer    FP-T495D107K016ATE125-MFG       5653.543      -2448.819     0        "CAP TANT 100UF 10% 16V 2917"                                                                                                  
C74        0.1uF_50V_0603          TopLayer    FP-CC0603-DA-MFG                5724.409      -2917.323     180      "CAP CER 0.1UF 50V X7R 0603"                                                                                                   
C73        4.7nF_50V_0402          TopLayer    FP-CC0402-MFG                   5478.346      -2596.457     270      "CAP CER 4700PF 50V X7R 0402"                                                                                                  
C72        DNI_1nF_50V_0402        TopLayer    FP-CL180-IPC_C                  5917.323      -2913.386     270      "Cap Ceramic 1nF 50V C0G ±5% SMD 0402 +125°C Paper T/R"                                                                        
C71        0.1uF_25V_0402          TopLayer    FP-0402-L_1_0_1-W_0_5_0_1-IPC_C 5500.000      -2799.213     180      "General Purpose Ceramic Capacitor, 0402, 100nF, 10%, X7R, 15%, 25V"                                                           
C70        2.2uF_16V_0402          TopLayer    FP-C1005-050-0_05-IPC_A         5599.741      -2925.197     180      "Multilayer Ceramic Capacitors 2.2µF ±10% 16V X5R SMD 0402"                                                                    
C69        1uF_16V_0402            TopLayer    FP-0402-L_1_0_0_05-W_0_5-IPC_A  5500.000      -2917.323     180      None                                                                                                                           
C68        0.1uF_50V_0603          TopLayer    FP-CC0603-DA-MFG                6003.937      -2956.693     180      "CAP CER 0.1UF 50V X7R 0603"                                                                                                   
R58        4.7K_0402               TopLayer    RESC1005X40X25LL05T05           5047.244      -1114.173     270      "Chip Resistor, 4.7 KOhm, +/- 1%, 0.1 W, -55 to 155 degC, 0402 (1005 Metric), RoHS, Tape and Reel"                             
R57        4.7K_0402               TopLayer    RESC1005X40X25LL05T05           5086.614      -1114.173     270      "Chip Resistor, 4.7 KOhm, +/- 1%, 0.1 W, -55 to 155 degC, 0402 (1005 Metric), RoHS, Tape and Reel"                             
R56        DNI_4.7K_0402           TopLayer    RESC1005X40X25LL05T05           4736.221      -1220.472     90       "Chip Resistor, 4.7 KOhm, +/- 1%, 0.1 W, -55 to 155 degC, 0402 (1005 Metric), RoHS, Tape and Reel"                             
R55        4.7K_0402               TopLayer    RESC1005X40X25LL05T05           4917.323      -1090.551     180      "Chip Resistor, 4.7 KOhm, +/- 1%, 0.1 W, -55 to 155 degC, 0402 (1005 Metric), RoHS, Tape and Reel"                             
R54        0_1%_0402               TopLayer    RESC1005X40X25LL05T05           4783.465      -1090.551     0        "Chip Resistor, 0 Ohm, 0.1 W, -55 to 155 degC, 0402 (1005 Metric), RoHS, Tape and Reel"                                        
R53        4.7K_0402               TopLayer    RESC1005X40X25LL05T05           4720.472      -1169.291     180      "Chip Resistor, 4.7 KOhm, +/- 1%, 0.1 W, -55 to 155 degC, 0402 (1005 Metric), RoHS, Tape and Reel"                             
R52        4.7K_0402               TopLayer    RESC1005X40X25LL05T05           4850.394      -1090.551     180      "Chip Resistor, 4.7 KOhm, +/- 1%, 0.1 W, -55 to 155 degC, 0402 (1005 Metric), RoHS, Tape and Reel"                             
R51        4.7K_0402               TopLayer    RESC1005X40X25LL05T05           5043.307      -1196.850     180      "Chip Resistor, 4.7 KOhm, +/- 1%, 0.1 W, -55 to 155 degC, 0402 (1005 Metric), RoHS, Tape and Reel"                             
R50        4.7K_0402               TopLayer    RESC1005X40X25LL05T05           4744.095      -1346.457     0        "Chip Resistor, 4.7 KOhm, +/- 1%, 0.1 W, -55 to 155 degC, 0402 (1005 Metric), RoHS, Tape and Reel"                             
C67        0.1uF_0402              TopLayer    CAPC1005X56X25NL10T15           5027.559      -1255.906     90       ""                                                                                                                             
C66        0.1uF_0402              TopLayer    CAPC1005X56X25NL10T15           5039.370      -1334.646     180      ""                                                                                                                             
C65        1uF_0402                TopLayer    FP-0402-L_1_0_0_05-W_0_5-IPC_C  4988.189      -1098.425     0        None                                                                                                                           
C64        0.1uF                   TopLayer    CAPC1608X87X45ML20T05           6681.102      -472.441      180      C0603X104K5RACAUTO                                                                                                             
C57        0.1uF                   TopLayer    CAPC1608X87X45ML20T05           6055.118      -448.819      0        C0603X104K5RACAUTO                                                                                                             
C56        10uF                    TopLayer    FP-MK212BG-MFG                  6677.165      -566.929      0        None                                                                                                                           
C55        10uF                    TopLayer    FP-MK212BG-MFG                  6055.118      -539.370      180      None                                                                                                                           
C54        0.1uF                   TopLayer    CAPC1608X87X45ML20T05           559.055       -397.638      270      C0603X104K5RACAUTO                                                                                                             
C43        0.1uF                   TopLayer    CAPC1608X87X45ML20T05           1114.173      -405.512      270      C0603X104K5RACAUTO                                                                                                             
C42        10uF                    TopLayer    FP-MK212BG-MFG                  472.441       -393.701      90       None                                                                                                                           
C41        10uF                    TopLayer    FP-MK212BG-MFG                  1244.094      -409.449      90       None                                                                                                                           
R49        0_1%_0402               TopLayer    RESC1005X40X25LL05T05           4248.032      -1838.583     0        "Chip Resistor, 0 Ohm, 0.1 W, -55 to 155 degC, 0402 (1005 Metric), RoHS, Tape and Reel"                                        
R48        0_1%_0402               TopLayer    RESC1005X40X25LL05T05           1401.575      -1295.276     270      "Chip Resistor, 0 Ohm, 0.1 W, -55 to 155 degC, 0402 (1005 Metric), RoHS, Tape and Reel"                                        
SKT10      0332-0-43-80-18-27-10-0 TopLayer    SolderSocket                    2464.724      -3271.653     90       "Solder socket for pin headers"                                                                                                
SKT9       0332-0-43-80-18-27-10-0 TopLayer    SolderSocket                    3023.622      -3165.354     90       "Solder socket for pin headers"                                                                                                
SKT8       0332-0-43-80-18-27-10-0 TopLayer    SolderSocket                    2584.724      -3271.653     90       "Solder socket for pin headers"                                                                                                
SKT7       0332-0-43-80-18-27-10-0 TopLayer    SolderSocket                    3023.622      -1566.929     90       "Solder socket for pin headers"                                                                                                
SKT6       0332-0-43-80-18-27-10-0 TopLayer    SolderSocket                    1425.197      -2366.142     90       "Solder socket for pin headers"                                                                                                
SKT5       0332-0-43-80-18-27-10-0 TopLayer    SolderSocket                    1425.197      -3165.354     90       "Solder socket for pin headers"                                                                                                
SKT4       0332-0-43-80-18-27-10-0 TopLayer    SolderSocket                    2940.945      -3271.653     90       "Solder socket for pin headers"                                                                                                
SKT3       0332-0-43-80-18-27-10-0 TopLayer    SolderSocket                    2822.835      -3271.653     90       "Solder socket for pin headers"                                                                                                
SKT2       0332-0-43-80-18-27-10-0 TopLayer    SolderSocket                    1425.197      -1566.929     90       "Solder socket for pin headers"                                                                                                
SKT1       0332-0-43-80-18-27-10-0 TopLayer    SolderSocket                    2704.724      -3271.653     90       "Solder socket for pin headers"                                                                                                
P1         TSW-105-05-L-S          TopLayer    SMTC-TSW-105-05-X-S             1614.961      -1200.787     180      "0.025" SQ Post Header, Through-hole, Vertical, -55 to 125 degC, 2.54 mm Pitch, 5-Pin, Male, RoHS"                             
R47        DNI_0_5%_1206           TopLayer    RESC3116X65X50ML20T20           3653.000      -1362.205     0        ""                                                                                                                             
J38        39-30-0040              TopLayer    FP-39-30-0040-MFG               6472.008      -1356.949     90       "CONN HEADER R/A 4POS 4.2MM"                                                                                                   
R46        DNI_0_5%_1206           TopLayer    RESC3116X65X50ML20T20           3653.000      -1125.984     0        ""                                                                                                                             
R45        0_5%_1206               TopLayer    RESC3116X65X50ML20T20           3653.000      -1248.032     0        ""                                                                                                                             
R44        DNI_0_5%_1206           TopLayer    RESC3116X65X50ML20T20           5952.756      -1677.165     180      ""                                                                                                                             
D19        STPS5L60S               TopLayer    FP-STPS5L60S-MFG                6251.968      -1685.039     0        "DIODE SCHOTTKY 60V 5A SMC"                                                                                                    
D12        STPS5L60S               TopLayer    FP-STPS5L60S-MFG                5960.630      -1342.520     90       "DIODE SCHOTTKY 60V 5A SMC"                                                                                                    
J37        "Single FPGA Conn"      TopLayer    SingleFPGAConn                  4309.097      -3085.975     90       ""                                                                                                                             
J36        "Single FPGA Conn"      TopLayer    SingleFPGAConn                  3409.043      -2340.449     0        ""                                                                                                                             
J35        "Single FPGA Conn"      TopLayer    SingleFPGAConn                  4309.097      -1604.766     270      ""                                                                                                                             
J34        "Single FPGA Conn"      TopLayer    SingleFPGAConn                  5283.953      -2340.449     180      ""                                                                                                                             
J31        SA53_Header             TopLayer    SA53_Header                     3013.188      -2365.934     180      ""                                                                                                                             
J13        "GNSS Header 16-pin"    TopLayer    GNSS_Header_16-pin              6406.398      -415.843      180      ""                                                                                                                             
J6         "GNSS Header 16-pin"    TopLayer    GNSS_Header_16-pin              827.855       -461.118      0        ""                                                                                                                             
R43        27_1%_0402              TopLayer    RESC1005X40X25NL05T05           6677.165      -811.024      90       ""                                                                                                                             
R42        27_1%_0402              TopLayer    RESC1005X40X25NL05T05           6803.150      -413.386      180      ""                                                                                                                             
D10        BLUE                    TopLayer    FP-LTST-C191TBKT-MFG            403.543       118.110       90       "LED BLUE CLEAR CHIP SMD"                                                                                                      
D9         BLUE                    TopLayer    FP-LTST-C191TBKT-MFG            334.646       118.110       90       "LED BLUE CLEAR CHIP SMD"                                                                                                      
D3         BLUE                    TopLayer    FP-LTST-C191TBKT-MFG            265.748       118.110       90       "LED BLUE CLEAR CHIP SMD"                                                                                                      
U16        NC7WV125K8X             TopLayer    SOP50P310X90-8N                 748.032       -3188.976     180      "Integrated Circuit"                                                                                                           
U12        NC7WV125K8X             TopLayer    SOP50P310X90-8N                 757.874       -2125.984     180      "Integrated Circuit"                                                                                                           
U11        NC7WV125K8X             TopLayer    SOP50P310X90-8N                 757.874       -2647.638     180      "Integrated Circuit"                                                                                                           
U8         NC7WV125K8X             TopLayer    SOP50P310X90-8N                 748.032       -1594.488     180      "Integrated Circuit"                                                                                                           
U6         IS32FL3207              TopLayer    IS32FL3207                      1033.465      -1259.842     0        ""                                                                                                                             
R41        4.7K                    TopLayer    RESC1608X55X30NL15T15           797.244       -1358.268     0        "Precision Thick Film Chip Resistor, 4.7 KOhm, +/- 1%, -55 to 155 degC, 0603 (1608 Metric), RoHS, Tape and Reel ERJ-3EKF4701V" 
R40        DNI_100k                TopLayer    FP-RC0603-0_55-MFG              799.213       -1102.362     0        "RES SMD 100K OHM 1% 1/10W 0603"                                                                                               
R39        "200 OHM"               TopLayer    RESC1608X55X30NL15T15           472.441       -19.685       90       ERJ-3EKF2000V                                                                                                                  
R38        "200 OHM"               TopLayer    RESC1608X55X30NL15T15           403.543       -19.685       90       ERJ-3EKF2000V                                                                                                                  
R36        "200 OHM"               TopLayer    RESC1608X55X30NL15T15           334.646       -19.685       90       ERJ-3EKF2000V                                                                                                                  
R35        "200 OHM"               TopLayer    RESC1608X55X30NL15T15           265.748       -19.685       90       ERJ-3EKF2000V                                                                                                                  
R34        49.9R                   TopLayer    RESC1608X55X25NL10T15           568.898       -3169.291     180      "General Purpose Chip Resistor, 49.9 Ohm, +/- 1%, -55 to 155 degC, 0603 (1608 Metric), RoHS, Tape and Reel"                    
R33        49.9R                   TopLayer    RESC1608X55X25NL10T15           580.709       -2106.299     180      "General Purpose Chip Resistor, 49.9 Ohm, +/- 1%, -55 to 155 degC, 0603 (1608 Metric), RoHS, Tape and Reel"                    
R32        4.7K                    TopLayer    RESC1608X55X30NL15T15           748.032       -3326.772     270      "Precision Thick Film Chip Resistor, 4.7 KOhm, +/- 1%, -55 to 155 degC, 0603 (1608 Metric), RoHS, Tape and Reel ERJ-3EKF4701V" 
R31        4.7K                    TopLayer    RESC1608X55X30NL15T15           826.772       -3326.772     270      "Precision Thick Film Chip Resistor, 4.7 KOhm, +/- 1%, -55 to 155 degC, 0603 (1608 Metric), RoHS, Tape and Reel ERJ-3EKF4701V" 
P3         "EXT GPIO"              TopLayer    HDR2X6_CEN                      5640.551      89.370        180      "Header, 6-Pin, Dual row"                                                                                                      
J4         1909763-1               TopLayer    TECO-1909763-1_V                412.894       -3169.291     270      "Ultra Miniature Coaxial Connector Jack, 60 V, 50 Ohm, -40 to 90 degC, RoHS, Tape and Reel"                                    
J2         1909763-1               TopLayer    TECO-1909763-1_V                412.894       -2106.299     270      "Ultra Miniature Coaxial Connector Jack, 60 V, 50 Ohm, -40 to 90 degC, RoHS, Tape and Reel"                                    
J3         1909763-1               TopLayer    TECO-1909763-1_V                412.894       -2627.953     270      "Ultra Miniature Coaxial Connector Jack, 60 V, 50 Ohm, -40 to 90 degC, RoHS, Tape and Reel"                                    
J1         1909763-1               TopLayer    TECO-1909763-1_V                412.894       -1574.803     270      "Ultra Miniature Coaxial Connector Jack, 60 V, 50 Ohm, -40 to 90 degC, RoHS, Tape and Reel"                                    
D18        155124M173200           TopLayer    155124M173200                   -190.453      -3413.386     90       "LED (Multiple)"                                                                                                               
D17        155124M173200           TopLayer    155124M173200                   -190.453      -2885.827     90       "LED (Multiple)"                                                                                                               
D16        155124M173200           TopLayer    155124M173200                   -190.453      -2350.394     90       "LED (Multiple)"                                                                                                               
D15        155124M173200           TopLayer    155124M173200                   -190.453      -1822.835     90       "LED (Multiple)"                                                                                                               
C40        0.1uF                   TopLayer    CAPC1608X87X45ML20T05           826.772       -1259.843     90       C0603X104K5RACAUTO                                                                                                             
C38        1uF                     TopLayer    FP-C0603C105K3PACTU-MFG         757.874       -1253.937     270      "CAP CER 1UF 25V X5R 0603"                                                                                                     
C33        0.1uF_0402              TopLayer    CAPC1005X56X25NL10T15           4980.315      -1413.386     180      ""                                                                                                                             
C32        0.1uF_0402              TopLayer    CAPC1005X56X25NL10T15           4980.315      -1374.016     180      ""                                                                                                                             
R37        10K                     TopLayer    RESC1608X55X30LL15T20           4586.614      -1376.472     180      "Chip Resistor, 10 KOhm, +/- 1%, 0.1 W, -55 to 155 degC, 0603 (1608 Metric), RoHS, Tape and Reel RMCF0603FT10K0"               
U15        RCB-F9T-1               TopLayer    GNSS                            6406.398      -258.362      180      "MOD, GPS"                                                                                                                     
C37        0.1uF                   TopLayer    CAPC1608X87X45ML20T05           6688.976      -161.417      180      C0603X104K5RACAUTO                                                                                                             
C36        0.1uF                   TopLayer    CAPC1608X87X45ML20T05           6127.664      -140.170      0        C0603X104K5RACAUTO                                                                                                             
C35        10uF                    TopLayer    FP-MK212BG-MFG                  6696.850      -236.220      0        None                                                                                                                           
C34        10uF                    TopLayer    FP-MK212BG-MFG                  6131.890      -215.055      180      None                                                                                                                           
D2         8240136                 TopLayer    SOT143-4L                       344.488       -2874.016     90       "TVS Diode WE-TVS-HS, VRWM=3.3V"                                                                                               
D1         8240136                 TopLayer    SOT143-4L                       344.488       -1797.244     90       "TVS Diode WE-TVS-HS, VRWM=3.3V"                                                                                               
R27        4.7K                    TopLayer    RESC1608X55X30NL15T15           1665.354      -1094.488     0        "Precision Thick Film Chip Resistor, 4.7 KOhm, +/- 1%, -55 to 155 degC, 0603 (1608 Metric), RoHS, Tape and Reel ERJ-3EKF4701V" 
R26        4.7K                    TopLayer    RESC1608X55X30NL15T15           1515.748      -1094.488     0        "Precision Thick Film Chip Resistor, 4.7 KOhm, +/- 1%, -55 to 155 degC, 0603 (1608 Metric), RoHS, Tape and Reel ERJ-3EKF4701V" 
U10        MAC-SA5X                TopLayer    SA53                            2258.562      -2399.291     180      "MOD, MAC, MAC-SA5X, ATOMIC CLOCK"                                                                                             
R14        4.7K                    TopLayer    RESC1608X55X30NL15T15           826.772       -1722.441     270      "Precision Thick Film Chip Resistor, 4.7 KOhm, +/- 1%, -55 to 155 degC, 0603 (1608 Metric), RoHS, Tape and Reel ERJ-3EKF4701V" 
U14        BME280                  TopLayer    FP-BME280-MFG                   5157.480      -1248.520     0        "SENSOR PRESSURE HUMIDITY TEMP"                                                                                                
U13        BNO055                  TopLayer    FP-BNO055-MFG                   4889.764      -1224.409     270      "IMU ACCEL/GYRO/MAG I2C 28LGA"                                                                                                 
U4         DS90LV028AQMA           TopLayer    M08A_L                          2185.039      -1218.992     0        "Automotive LVDS Dual Differential Line Receiver, 8-pin Narrow SOIC"                                                           
U3         DS90LV027AQMA           TopLayer    M08A_N                          2889.764      -1214.465     0        "Automotive LVDS Dual Differential Driver, 8-pin Narrow SOIC"                                                                  
R25        49.9R                   TopLayer    RESC1608X55X25NL10T15           570.866       -1574.803     180      "General Purpose Chip Resistor, 49.9 Ohm, +/- 1%, -55 to 155 degC, 0603 (1608 Metric), RoHS, Tape and Reel"                    
R17        4.7K                    TopLayer    RESC1608X55X30NL15T15           757.874       -2785.433     270      "Precision Thick Film Chip Resistor, 4.7 KOhm, +/- 1%, -55 to 155 degC, 0603 (1608 Metric), RoHS, Tape and Reel ERJ-3EKF4701V" 
R13        27_1%_0402              TopLayer    RESC1005X40X25NL05T05           6964.567      -464.567      270      ""                                                                                                                             
R12        110R                    TopLayer    RESC1609X50X30NL10T20           1998.032      -1169.780     270      ""                                                                                                                             
R11        4.7K                    TopLayer    RESC1608X55X25LL10T15           2669.291      -1291.339     0        "Chip Resistor, 4.7 KOhm, +/- 1%, 0.1 W, -55 to 155 degC, 0603 (1608 Metric), RoHS, Tape and Reel RC0603FR-074K7L"             
R10        4.7K                    TopLayer    RESC1608X55X25LL10T15           2690.945      -1188.976     0        "Chip Resistor, 4.7 KOhm, +/- 1%, 0.1 W, -55 to 155 degC, 0603 (1608 Metric), RoHS, Tape and Reel RC0603FR-074K7L"             
C31        0.1uF                   TopLayer    CAPC1608X87X45ML20T05           5285.433      -1148.126     270      C0603X104K5RACAUTO                                                                                                             
C30        0.1uF                   TopLayer    CAPC1608X87X45ML20T05           5159.449      -1120.567     180      C0603X104K5RACAUTO                                                                                                             
C29        0.1uF                   TopLayer    CAPC1608X87X45ML20T05           679.134       -3326.772     270      C0603X104K5RACAUTO                                                                                                             
C28        0.1uF                   TopLayer    CAPC1608X87X45ML20T05           688.976       -2244.094     270      C0603X104K5RACAUTO                                                                                                             
C27        0.1uF                   TopLayer    CAPC1608X87X45ML20T05           688.976       -2785.433     270      C0603X104K5RACAUTO                                                                                                             
C26        0.1uF                   TopLayer    CAPC1608X87X45ML20T05           679.134       -1722.441     270      C0603X104K5RACAUTO                                                                                                             
C24        0.1uF                   TopLayer    CAPC1608X87X45ML20T05           2370.079      -1082.677     0        C0603X104K5RACAUTO                                                                                                             
C23        0.1uF                   TopLayer    CAPC1608X87X45ML20T05           2667.323      -1120.567     0        C0603X104K5RACAUTO                                                                                                             
AN1        RF2-49B-T-00-50-G-HDW   TopLayer    AMPH-901-143-6RFX_V             -84.645       -1573.323     180      "Coaxial connector, 50 Ohm, -65 to 165 degC, 5-Pin THD, RoHS, Bulk"                                                            
AN3        RF2-49B-T-00-50-G-HDW   TopLayer    AMPH-901-143-6RFX_V             -84.646       -2636.299     180      "Coaxial connector, 50 Ohm, -65 to 165 degC, 5-Pin THD, RoHS, Bulk"                                                            
AN2        RF2-49B-T-00-50-G-HDW   TopLayer    AMPH-901-143-6RFX_V             -84.646       -2104.803     180      "Coaxial connector, 50 Ohm, -65 to 165 degC, 5-Pin THD, RoHS, Bulk"                                                            
AN4        RF2-49B-T-00-50-G-HDW   TopLayer    AMPH-901-143-6RFX_V             -84.645       -3167.811     180      "Coaxial connector, 50 Ohm, -65 to 165 degC, 5-Pin THD, RoHS, Bulk"                                                            
U7         AT24MAC402-STUM-T       TopLayer    FP-5TS1-IPC_C                   4606.299      -1258.362     270      "IC EEPROM 2K I2C 1MHZ SOT23-5"                                                                                                
C25        0.1uF                   TopLayer    CAPC1608X87X45ML20T05           4478.346      -1258.362     270      C0603X104K5RACAUTO                                                                                                             
R16        4.7K                    TopLayer    RESC1608X55X30NL15T15           836.614       -2785.433     270      "Precision Thick Film Chip Resistor, 4.7 KOhm, +/- 1%, -55 to 155 degC, 0603 (1608 Metric), RoHS, Tape and Reel ERJ-3EKF4701V" 
R15        4.7K                    TopLayer    RESC1608X55X30NL15T15           748.032       -1722.441     270      "Precision Thick Film Chip Resistor, 4.7 KOhm, +/- 1%, -55 to 155 degC, 0603 (1608 Metric), RoHS, Tape and Reel ERJ-3EKF4701V" 
R5         1.21_1%_0402            TopLayer    RESC0402(1005)_N                5677.166      -2220.472     270      "1R21 0.063W 1% 0402 (1005 Metric)  SMD"                                                                                       
U9         RCB-F9T                 TopLayer    GNSS                            827.855       -618.598      0        "MOD, GPS"                                                                                                                     
U5         HTST-105-01-L-DV-A      TopLayer    SAMTEC_HTST-105-01-L-DV-A       5892.913      -3300.394     0        "CONN, HDR, 2X5, VERT, 0.1IN  SHROUDED, SMT, HTSH SERIES"                                                                      
U2         INA219BIDR              TopLayer    FP-D0008A-MFG                   5511.811      -1263.780     270      "IC MONITOR PWR/CURR BIDIR 8-SOIC"                                                                                             
U1         MIC24052YJL-TR          TopLayer    QFN28_5X6_MCH                   5847.964      -2134.404     90       "No Description Available"                                                                                                     
R30        4.7K                    TopLayer    RESC1608X55X30NL15T15           757.874       -2244.094     270      "Precision Thick Film Chip Resistor, 4.7 KOhm, +/- 1%, -55 to 155 degC, 0603 (1608 Metric), RoHS, Tape and Reel ERJ-3EKF4701V" 
R29        4.7K                    TopLayer    RESC1608X55X30NL15T15           826.772       -2244.095     270      "Precision Thick Film Chip Resistor, 4.7 KOhm, +/- 1%, -55 to 155 degC, 0603 (1608 Metric), RoHS, Tape and Reel ERJ-3EKF4701V" 
R28        49.9R                   TopLayer    RESC1608X55X25NL10T15           580.709       -2627.953     180      "General Purpose Chip Resistor, 49.9 Ohm, +/- 1%, -55 to 155 degC, 0603 (1608 Metric), RoHS, Tape and Reel"                    
R24        ERJ-2GE0R00X            TopLayer    RESC1005X04N                    1330.709      -3472.441     0        "RES, 0. OHM, 1%, 1/16W, TF, AEC-Q200, 0402"                                                                                   
R23        ERJ-2GE0R00X            TopLayer    RESC1005X04N                    1330.709      -3429.134     0        "RES, 0. OHM, 1%, 1/16W, TF, AEC-Q200, 0402"                                                                                   
R22        ERJ-3EKF4701V           TopLayer    RESC1608X50N                    1134.252      -2636.315     180      "RES, 4.7K, 1%, 1/10W, TF, 0603"                                                                                               
R21        CRCW080533R0FKEA        TopLayer    RESC2012X50N                    6370.079      -3429.134     270      "RES, 33 OHM, 1%, 1/8W, TF, 0805"                                                                                              
R20        CRCW080533R0FKEA        TopLayer    RESC2012X50N                    6551.181      -3425.197     270      "RES, 33 OHM, 1%, 1/8W, TF, 0805"                                                                                              
R19        CRCW080533R0FKEA        TopLayer    RESC2012X50N                    5361.624      -3478.796     0        "RES, 33 OHM, 1%, 1/8W, TF, 0805"                                                                                              
R18        CRCW080533R0FKEA        TopLayer    RESC2012X50N                    5365.561      -3317.379     0        "RES, 33 OHM, 1%, 1/8W, TF, 0805"                                                                                              
R9         1.21_1%_0402            TopLayer    RESC1005X40X25LL10T10           5944.882      -2299.213     90       ""                                                                                                                             
R8         2mOhm_1%_1206           TopLayer    RESC3216X89X64NL25T25           6409.449      -2059.055     90       ""                                                                                                                             
R7         2mOhm_1%_1206           TopLayer    RESC3216X89X64NL25T25           5767.717      -1452.756     90       ""                                                                                                                             
R6         2.21_1%_0402            TopLayer    RESC1005X40X25ML05T10           6066.929      -2322.835     180      ""                                                                                                                             
R4         1.21_1%_0402            TopLayer    RESC0402(1005)_N                6169.291      -2397.638     0        "1R21 0.063W 1% 0402 (1005 Metric)  SMD"                                                                                       
R3         4.7K_0402               TopLayer    RESC1005X40X25LL05T05           5629.921      -2055.118     0        "Chip Resistor, 4.7 KOhm, +/- 1%, 0.1 W, -55 to 155 degC, 0402 (1005 Metric), RoHS, Tape and Reel"                             
R2         4.7K_0402               TopLayer    RESC1005X40X25LL05T05           5629.921      -2090.551     0        "Chip Resistor, 4.7 KOhm, +/- 1%, 0.1 W, -55 to 155 degC, 0402 (1005 Metric), RoHS, Tape and Reel"                             
R1         200_1%_0402             TopLayer    FP-ERJ2RK-IPC_A                 6862.205      -3224.409     180      "RES SMD 200 OHM 1% 1/10W 0402"                                                                                                
P2         PCIex4                  TopLayer    PCIE_4LANE_EDGE                 2161.417      -4004.518     0        "PCIE x4 Edge Connector,OrCAD Symbol,NC"                                                                                       
L2         2.2uH_10A               TopLayer    FP-IHLP-2525EZ-FP_2_413x3-MFG   6129.921      -2759.843     0        "Commercial Inductors, High Saturation Series 2.2uH 10A 13.6mO 20%"                                                            
L1         2.2uH_10A               TopLayer    FP-IHLP-2525EZ-FP_2_413x3-MFG   6165.354      -2157.480     0        "Commercial Inductors, High Saturation Series 2.2uH 10A 13.6mO 20%"                                                            
F1         FUSE_0603_5.00A         TopLayer    FUSM1608X60N                    5948.819      -1594.488     180      "FUSE SLOW 5.00A 32V M 0603"                                                                                                   
D14        155124M173200           TopLayer    155124M173200                   -190.453      -1084.646     90       "LED (Multiple)"                                                                                                               
D13        155124M173200           TopLayer    155124M173200                   -190.453      -651.575      90       "LED (Multiple)"                                                                                                               
D11        BLUE                    TopLayer    FP-LTST-C191TBKT-MFG            472.441       118.110       90       "LED BLUE CLEAR CHIP SMD"                                                                                                      
D8         BAT54SW                 TopLayer    SOT65P210X110-3N                6370.079      -3248.032     270      "DIO, SCHOTTKY, BAT54S, DUAL SERIES, 30V, 200MA, SC-70"                                                                        
D7         BAT54SW                 TopLayer    SOT65P210X110-3N                6557.087      -3249.016     270      "DIO, SCHOTTKY, BAT54S, DUAL SERIES, 30V, 200MA, SC-70"                                                                        
D6         BAT54SW                 TopLayer    SOT65P210X110-3N                5195.286      -3478.796     0        "DIO, SCHOTTKY, BAT54S, DUAL SERIES, 30V, 200MA, SC-70"                                                                        
D5         BAT54SW                 TopLayer    SOT65P210X110-3N                5196.270      -3317.379     0        "DIO, SCHOTTKY, BAT54S, DUAL SERIES, 30V, 200MA, SC-70"                                                                        
D4         SML-LX0603IW-TR         TopLayer    FP-SML-LX0603IW-TR-MFG          6728.346      -3232.284     180      "LED RED DIFFUSED SMD"                                                                                                         
C63        0.1uF                   TopLayer    CAPC1608X87X45ML20T05           3481.060      -1014.822     270      C0603X104K5RACAUTO                                                                                                             
C62        CAP_0805_10UF_25V       TopLayer    CAPC2012X14N                    3574.803      -1003.937     90       "CAP, CER, 10.UF, 25V, 10%, X5R, 0805"                                                                                         
C61        0.1uF                   TopLayer    CAPC1608X87X45ML20T05           984.252       -953.244      90       C0603X104K5RACAUTO                                                                                                             
C60        10uF                    TopLayer    FP-MK212BG-MFG                  895.669       -943.402      270      None                                                                                                                           
C59        0.1uF                   TopLayer    CAPC1608X87X45ML20T05           1141.732      -766.236      90       C0603X104K5RACAUTO                                                                                                             
C58        10uF                    TopLayer    FP-MK212BG-MFG                  1230.315      -760.331      270      None                                                                                                                           
C53        CAP_0402_0.1UF_50V      BottomLayer CAPC1005X06N                    2734.410      -3806.000     90       "CAP, CER, 0.1UF, 50V, 10%, X7R, AEC-Q200, 0402"                                                                               
C52        CAP_0402_0.1UF_50V      BottomLayer CAPC1005X06N                    2694.410      -3806.000     90       "CAP, CER, 0.1UF, 50V, 10%, X7R, AEC-Q200, 0402"                                                                               
C51        CAP_0402_0.1UF_50V      BottomLayer CAPC1005X06N                    2569.410      -3806.000     90       "CAP, CER, 0.1UF, 50V, 10%, X7R, AEC-Q200, 0402"                                                                               
C50        CAP_0402_0.1UF_50V      BottomLayer CAPC1005X06N                    2534.410      -3806.000     90       "CAP, CER, 0.1UF, 50V, 10%, X7R, AEC-Q200, 0402"                                                                               
C49        CAP_0402_0.1UF_50V      BottomLayer CAPC1005X06N                    2419.410      -3806.000     90       "CAP, CER, 0.1UF, 50V, 10%, X7R, AEC-Q200, 0402"                                                                               
C48        CAP_0402_0.1UF_50V      BottomLayer CAPC1005X06N                    2379.410      -3806.000     90       "CAP, CER, 0.1UF, 50V, 10%, X7R, AEC-Q200, 0402"                                                                               
C47        CAP_0402_0.1UF_50V      BottomLayer CAPC1005X06N                    2226.410      -3806.000     90       "CAP, CER, 0.1UF, 50V, 10%, X7R, AEC-Q200, 0402"                                                                               
C46        CAP_0402_0.1UF_50V      BottomLayer CAPC1005X06N                    2183.410      -3806.000     90       "CAP, CER, 0.1UF, 50V, 10%, X7R, AEC-Q200, 0402"                                                                               
C45        CAP_0402_0.1UF_50V      BottomLayer CAPC1005X06N                    2104.410      -3806.000     90       "CAP, CER, 0.1UF, 50V, 10%, X7R, AEC-Q200, 0402"                                                                               
C44        CAP_0402_0.1UF_50V      BottomLayer CAPC1005X06N                    2064.410      -3806.000     90       "CAP, CER, 0.1UF, 50V, 10%, X7R, AEC-Q200, 0402"                                                                               
C22        10uF_16V_0603           TopLayer    FP-0603-L_1_6_0_2-W_0_8_0-MFG   6503.937      -2248.032     270      "Multilayer Ceramic Capacitor 10uF 16V X5R 20% SMD 0603 T/R"                                                                   
C21        0.1uF_0402              TopLayer    CAPC1005X56X25NL10T15           6437.008      -2255.905     90       ""                                                                                                                             
C20        10uF_16V_0603           TopLayer    FP-0603-L_1_6_0_2-W_0_8_0-MFG   5346.457      -1338.583     180      "Multilayer Ceramic Capacitor 10uF 16V X5R 20% SMD 0603 T/R"                                                                   
C19        0.1uF_0402              TopLayer    CAPC1005X56X25NL10T15           5342.520      -1413.386     0        ""                                                                                                                             
C18        0.1uF_25V_0402          TopLayer    FP-0402-L_1_0_1-W_0_5_0_1-IPC_C 6818.898      -2072.223     270      "General Purpose Ceramic Capacitor, 0402, 100nF, 10%, X7R, 15%, 25V"                                                           
C17        1uF_16V_0402            TopLayer    FP-0402-L_1_0_0_05-W_0_5-IPC_A  6833.617      -1851.796     90       None                                                                                                                           
C16        2.2uF_16V_0402          TopLayer    FP-C1005-050-0_05-IPC_A         6669.291      -2074.803     270      "Multilayer Ceramic Capacitors 2.2µF ±10% 16V X5R SMD 0402"                                                                    
C15        10uF_16V_0603           TopLayer    FP-0603-L_1_6_0_2-W_0_8_0-MFG   6744.095      -2074.803     270      "Multilayer Ceramic Capacitor 10uF 16V X5R 20% SMD 0603 T/R"                                                                   
C14        100uF_16V_2917          TopLayer    FP-T495D107K016ATE125-MFG       6602.362      -1834.646     270      "CAP TANT 100UF 10% 16V 2917"                                                                                                  
C13        47uF_16V_1206           TopLayer    FP-C3216-160-0_2-MFG            6755.905      -1846.457     90       "Multilayer Ceramic Capacitors 47uF ±20% 16V X5R SMD 1206"                                                                     
C12        4.7uF_50V_1206          TopLayer    FP-GRM31C-0_2-e0_3_0_8-IPC_C    5866.142      -1885.827     90       "Chip Multilayer Ceramic Capacitors for General Purpose, 1206, 4.7uF, X7R, 15%, 10%, 50V"                                      
C11        4.7uF_50V_1206          TopLayer    FP-GRM31C-0_2-e0_3_0_8-IPC_C    5960.630      -1885.827     90       "Chip Multilayer Ceramic Capacitors for General Purpose, 1206, 4.7uF, X7R, 15%, 10%, 50V"                                      
C10        100uF_16V_2917          TopLayer    FP-T495D107K016ATE125-MFG       6173.228      -1913.386     180      "CAP TANT 100UF 10% 16V 2917"                                                                                                  
C9         0.1uF_50V_0603          TopLayer    FP-CC0603-DA-MFG                5992.126      -2397.638     270      "CAP CER 0.1UF 50V X7R 0603"                                                                                                   
C8         4.7nF_50V_0402          TopLayer    FP-CC0402-MFG                   5602.362      -1996.063     270      "CAP CER 4700PF 50V X7R 0402"                                                                                                  
C7         DNI_1nF_50V_0402        TopLayer    FP-CL180-IPC_C                  5913.386      -2374.016     180      "Cap Ceramic 1nF 50V C0G ±5% SMD 0402 +125°C Paper T/R"                                                                        
C6         0.1uF_25V_0402          TopLayer    FP-0402-L_1_0_1-W_0_5_0_1-IPC_C 5625.984      -2145.669     90       "General Purpose Ceramic Capacitor, 0402, 100nF, 10%, X7R, 15%, 25V"                                                           
C5         2.2uF_16V_0402          TopLayer    FP-C1005-050-0_05-IPC_A         5535.433      -2232.284     90       "Multilayer Ceramic Capacitors 2.2µF ±10% 16V X5R SMD 0402"                                                                    
C4         1uF_16V_0402            TopLayer    FP-0402-L_1_0_0_05-W_0_5-IPC_A  5614.173      -2216.535     180      None                                                                                                                           
C3         0.1uF_50V_0603          TopLayer    FP-CC0603-DA-MFG                6169.291      -2334.646     180      "CAP CER 0.1UF 50V X7R 0603"                                                                                                   
C2         0.1uF                   TopLayer    CAPC1608X87X45ML20T05           5681.102      -1204.724     270      C0603X104K5RACAUTO                                                                                                             
C1         CAP_0805_10UF_25V       TopLayer    CAPC2012X14N                    5775.591      -1208.661     90       "CAP, CER, 10.UF, 25V, 10%, X5R, 0805"                                                                                         
